# T6G (Grand Teton) — schematic netlist excerpt (pin names and nets, part order shuffled) for the footprints in the layout excerpt that follows; sources: Cadence DE-HDL packaged netlist, KiCad conversion of 04192023_DAF0TMB3IC0_F0TG_MB_C_brd_V02_OCP.brd

PR373  Q_RES  5.6 1% CHIP  pkg 0402LF  page 223 : A = SW_PVDDIO_P1_BOOT3 ; B = SW_PVDDIO_P1_BOOT3_R
PR387  Q_RES  0 5% CHIP  pkg 0402LF  page 225 : A = PVDD11_S3_P1_PVCC ; B = P5V_AUX

(kicad_pcb
	(version 20260206)
	(generator "pcbnew")
	(generator_version "10.0")
	(general
		(thickness 1.6)
		(legacy_teardrops no)
	)
	(paper "A4")
	(title_block
		(title "04192023_DAF0TMB3IC0_F0TG_MB_C_brd_V02_OCP.brd")
		(comment 1 "Grand Teton / footprints 3777-3778 of 8354")
	)
	(layers
		(0 "F.Cu" signal "TOP")
		(4 "In1.Cu" signal "GND")
		(6 "In2.Cu" signal "IN1")
		(8 "In3.Cu" signal "GND1")
		(10 "In4.Cu" signal "IN2")
		(12 "In5.Cu" signal "GND2")
		(14 "In6.Cu" signal "IN3")
		(16 "In7.Cu" signal "GND3")
		(18 "In8.Cu" signal "VCC")
		(20 "In9.Cu" signal "VCC1")
		(22 "In10.Cu" signal "GND4")
		(24 "In11.Cu" signal "IN4")
		(26 "In12.Cu" signal "GND5")
		(28 "In13.Cu" signal "IN5")
		(30 "In14.Cu" signal "GND6")
		(32 "In15.Cu" signal "IN6")
		(34 "In16.Cu" signal "GND7")
		(2 "B.Cu" signal "BOTTOM")
		(9 "F.Adhes" user "F.Adhesive")
		(11 "B.Adhes" user "B.Adhesive")
		(13 "F.Paste" user "Package Geometry/Pastemask Top")
		(15 "B.Paste" user "Package Geometry/Pastemask Bottom")
		(5 "F.SilkS" user "Ref Des/Silkscreen Top")
		(7 "B.SilkS" user "Ref Des/Silkscreen Bottom")
		(1 "F.Mask" user "Board Geometry/Soldermask Top")
		(3 "B.Mask" user "Board Geometry/Soldermask Bottom")
		(17 "Dwgs.User" user "User.Drawings")
		(19 "Cmts.User" user "User.Comments")
		(21 "Eco1.User" user "User.Eco1")
		(23 "Eco2.User" user "User.Eco2")
		(25 "Edge.Cuts" user "Board Geometry/Outline")
		(27 "Margin" user)
		(31 "F.CrtYd" user "Package Geometry/Place Bound Top")
		(29 "B.CrtYd" user "Package Geometry/Place Bound Bottom")
		(35 "F.Fab" user "Ref Des/Assembly Top")
		(33 "B.Fab" user "Ref Des/Assembly Bottom")
	)
	(footprint ""
		(layer "F.Cu")
		(at 37.64026 -351.372932 90)
		(property "Reference" "PR373"
			(at 0 0 90)
			(layer "F.SilkS")
			(hide yes)
			(effects
				(font
					(size 1.27 1.27)
				)
			)
		)
		(property "Value" ""
			(at 0 0 90)
			(layer "F.Fab")
			(effects
				(font
					(size 1.27 1.27)
				)
			)
		)
		(duplicate_pad_numbers_are_jumpers no)
		(fp_line
			(start 0.7874 -0.4064)
			(end 0.7874 0.4064)
			(stroke
				(width 0.1524)
				(type default)
			)
			(layer "F.SilkS")
		)
		(fp_line
			(start -0.7874 -0.4064)
			(end 0.7874 -0.4064)
			(stroke
				(width 0.1524)
				(type default)
			)
			(layer "F.SilkS")
		)
		(fp_line
			(start 0.7874 0.4064)
			(end -0.7874 0.4064)
			(stroke
				(width 0.1524)
				(type default)
			)
			(layer "F.SilkS")
		)
		(fp_line
			(start -0.7874 0.4064)
			(end -0.7874 -0.4064)
			(stroke
				(width 0.1524)
				(type default)
			)
			(layer "F.SilkS")
		)
		(fp_line
			(start -0.12065 -0.305054)
			(end -0.12065 -0.2794)
			(stroke
				(width 0.1)
				(type default)
			)
			(layer "F.Fab")
		)
		(fp_line
			(start -0.67945 -0.305054)
			(end -0.12065 -0.305054)
			(stroke
				(width 0.1)
				(type default)
			)
			(layer "F.Fab")
		)
		(fp_line
			(start 0.67945 -0.3048)
			(end 0.67945 0.3048)
			(stroke
				(width 0.1)
				(type default)
			)
			(layer "F.Fab")
		)
		(fp_line
			(start 0.12065 -0.3048)
			(end 0.67945 -0.3048)
			(stroke
				(width 0.1)
				(type default)
			)
			(layer "F.Fab")
		)
		(fp_line
			(start 0.12065 -0.2794)
			(end 0.12065 -0.3048)
			(stroke
				(width 0.1)
				(type default)
			)
			(layer "F.Fab")
		)
		(fp_line
			(start -0.12065 -0.2794)
			(end 0.12065 -0.2794)
			(stroke
				(width 0.1)
				(type default)
			)
			(layer "F.Fab")
		)
		(fp_line
			(start 0.120396 0.2794)
			(end -0.12065 0.2794)
			(stroke
				(width 0.1)
				(type default)
			)
			(layer "F.Fab")
		)
		(fp_line
			(start -0.12065 0.2794)
			(end -0.12065 0.3048)
			(stroke
				(width 0.1)
				(type default)
			)
			(layer "F.Fab")
		)
		(fp_line
			(start 0.67945 0.3048)
			(end 0.120396 0.3048)
			(stroke
				(width 0.1)
				(type default)
			)
			(layer "F.Fab")
		)
		(fp_line
			(start 0.120396 0.3048)
			(end 0.120396 0.2794)
			(stroke
				(width 0.1)
				(type default)
			)
			(layer "F.Fab")
		)
		(fp_line
			(start -0.12065 0.3048)
			(end -0.67945 0.3048)
			(stroke
				(width 0.1)
				(type default)
			)
			(layer "F.Fab")
		)
		(fp_line
			(start -0.67945 0.3048)
			(end -0.67945 -0.305054)
			(stroke
				(width 0.1)
				(type default)
			)
			(layer "F.Fab")
		)
		(pad "1" smd circle
			(at -0.40005 0 90)
			(size 0 0)
			(layers "F.Cu" "F.Mask" "F.Paste")
			(net "SW_PVDDIO_P1_BOOT3")
		)
		(pad "2" smd circle
			(at 0.40005 0 90)
			(size 0 0)
			(layers "F.Cu" "F.Mask" "F.Paste")
			(net "SW_PVDDIO_P1_BOOT3_R")
		)
	)
	(footprint ""
		(layer "F.Cu")
		(at 177.223674 -353.958652 90)
		(property "Reference" "PR387"
			(at 0 0 90)
			(layer "F.SilkS")
			(hide yes)
			(effects
				(font
					(size 1.27 1.27)
				)
			)
		)
		(property "Value" ""
			(at 0 0 90)
			(layer "F.Fab")
			(effects
				(font
					(size 1.27 1.27)
				)
			)
		)
		(duplicate_pad_numbers_are_jumpers no)
		(fp_line
			(start 0.7874 -0.4064)
			(end 0.7874 0.4064)
			(stroke
				(width 0.1524)
				(type default)
			)
			(layer "F.SilkS")
		)
		(fp_line
			(start -0.7874 -0.4064)
			(end 0.7874 -0.4064)
			(stroke
				(width 0.1524)
				(type default)
			)
			(layer "F.SilkS")
		)
		(fp_line
			(start 0.7874 0.4064)
			(end -0.7874 0.4064)
			(stroke
				(width 0.1524)
				(type default)
			)
			(layer "F.SilkS")
		)
		(fp_line
			(start -0.7874 0.4064)
			(end -0.7874 -0.4064)
			(stroke
				(width 0.1524)
				(type default)
			)
			(layer "F.SilkS")
		)
		(fp_line
			(start -0.12065 -0.305054)
			(end -0.12065 -0.2794)
			(stroke
				(width 0.1)
				(type default)
			)
			(layer "F.Fab")
		)
		(fp_line
			(start -0.67945 -0.305054)
			(end -0.12065 -0.305054)
			(stroke
				(width 0.1)
				(type default)
			)
			(layer "F.Fab")
		)
		(fp_line
			(start 0.67945 -0.3048)
			(end 0.67945 0.3048)
			(stroke
				(width 0.1)
				(type default)
			)
			(layer "F.Fab")
		)
		(fp_line
			(start 0.12065 -0.3048)
			(end 0.67945 -0.3048)
			(stroke
				(width 0.1)
				(type default)
			)
			(layer "F.Fab")
		)
		(fp_line
			(start 0.12065 -0.2794)
			(end 0.12065 -0.3048)
			(stroke
				(width 0.1)
				(type default)
			)
			(layer "F.Fab")
		)
		(fp_line
			(start -0.12065 -0.2794)
			(end 0.12065 -0.2794)
			(stroke
				(width 0.1)
				(type default)
			)
			(layer "F.Fab")
		)
		(fp_line
			(start 0.120396 0.2794)
			(end -0.12065 0.2794)
			(stroke
				(width 0.1)
				(type default)
			)
			(layer "F.Fab")
		)
		(fp_line
			(start -0.12065 0.2794)
			(end -0.12065 0.3048)
			(stroke
				(width 0.1)
				(type default)
			)
			(layer "F.Fab")
		)
		(fp_line
			(start 0.67945 0.3048)
			(end 0.120396 0.3048)
			(stroke
				(width 0.1)
				(type default)
			)
			(layer "F.Fab")
		)
		(fp_line
			(start 0.120396 0.3048)
			(end 0.120396 0.2794)
			(stroke
				(width 0.1)
				(type default)
			)
			(layer "F.Fab")
		)
		(fp_line
			(start -0.12065 0.3048)
			(end -0.67945 0.3048)
			(stroke
				(width 0.1)
				(type default)
			)
			(layer "F.Fab")
		)
		(fp_line
			(start -0.67945 0.3048)
			(end -0.67945 -0.305054)
			(stroke
				(width 0.1)
				(type default)
			)
			(layer "F.Fab")
		)
		(pad "1" smd circle
			(at -0.40005 0 90)
			(size 0 0)
			(layers "F.Cu" "F.Mask" "F.Paste")
			(net "PVDD11_S3_P1_PVCC")
		)
		(pad "2" smd circle
			(at 0.40005 0 90)
			(size 0 0)
			(layers "F.Cu" "F.Mask" "F.Paste")
			(net "P5V_AUX")
		)
	)
)
